FILE_TYPE = MACRO_DRAWING;
SET COLOR_WIRE YELLOW;
SET COLOR_PROP ORANGE;
SET COLOR_DOT WHITE;
SET COLOR_ARC YELLOW;
SET COLOR_BODY GREEN;
SET COLOR_NOTE PURPLE;
SET PROP_DISPLAY VALUE;
SET PAGE_NUMBER P374;
FORCEADD OFFPAGE..1
(-9075 1525);
PAINT AQUA (-9075 1525);
FORCEPROP 2 LAST $XR0 82 
J 0
(-9296 1525);
DISPLAY 0.638298 (-9296 1525);
PAINT MONO (-9296 1525);
FORCEPROP 2 LAST CDS_LIB standard
J 0
(-9075 1525);
DISPLAY INVISIBLE (-9075 1525);
FORCEPROP 1 LAST OFFPAGE TRUE
J 0
(-8750 1400);
DISPLAY 0.872340 (-8750 1400);
PAINT AQUA (-8750 1400);
DISPLAY INVISIBLE (-8750 1400);
FORCEPROP 1 LAST COMMENT_BODY TRUE
J 0
(-8950 1425);
DISPLAY 0.872340 (-8950 1425);
PAINT GREEN (-8950 1425);
DISPLAY INVISIBLE (-8950 1425);
FORCEPROP 2 LAST PATH I1
J 0
(-9325 1575);
DISPLAY 0.680851 (-9325 1575);
DISPLAY INVISIBLE (-9325 1575);
FORCEADD UNIVERSAL_GND..1
(-7925 5100);
FORCEPROP 3 LASTPIN (-7925 5150) SIG_NAME GND\g
J 0
(-7915 5160);
DISPLAY 0.659574 (-7915 5160);
PAINT MONO (-7915 5160);
DISPLAY INVISIBLE (-7915 5160);
FORCEPROP 2 LAST CDS_LIB pure_quanta_power
J 0
(-7925 5100);
DISPLAY INVISIBLE (-7925 5100);
FORCEPROP 1 LAST HDL_POWER GND
J 1
(-7900 5025);
DISPLAY 0.872340 (-7900 5025);
PAINT GREEN (-7900 5025);
DISPLAY INVISIBLE (-7900 5025);
FORCEPROP 1 LAST PATH I10
J 0
(-7850 5100);
DISPLAY 0.872340 (-7850 5100);
PAINT AQUA (-7850 5100);
DISPLAY INVISIBLE (-7850 5100);
FORCEADD Q_LED..1
R 2
(-6900 1850);
FORCEPROP 1 LAST LOCATION D76
J 0
(-7000 1775);
DISPLAY 0.723404 (-7000 1775);
PAINT GREEN (-7000 1775);
FORCEPROP 0 LAST $SEC 1
J 0
(-7000 1825);
DISPLAY INVISIBLE (-7000 1825);
FORCEPROP 0 LAST CDS_SEC 1
J 0
(-7000 1825);
DISPLAY INVISIBLE (-7000 1825);
FORCEPROP 0 LASTPIN (-6750 1850) $PN A
J 0
(-6740 1860);
DISPLAY 0.808511 (-6740 1860);
FORCEPROP 0 LASTPIN (-7050 1850) $PN C
J 2
(-7060 1860);
DISPLAY 0.808511 (-7060 1860);
FORCEPROP 2 LAST MANUF_PN LTST-C281TBKT-5A
J 0
(-7000 1575);
DISPLAY 0.638298 (-7000 1575);
FORCEPROP 1 LAST MATERIAL IC
J 0
(-6875 1675);
DISPLAY 0.723404 (-6875 1675);
PAINT GREEN (-6875 1675);
FORCEPROP 0 LAST PACK_TYPE SMLF
J 0
(-7000 1675);
DISPLAY 0.638298 (-7000 1675);
FORCEPROP 2 LAST COLOR LED_BLUE
J 0
(-7000 1725);
DISPLAY 0.638298 (-7000 1725);
FORCEPROP 2 LAST CDS_LIB pure_quanta
J 0
(-6900 1850);
DISPLAY INVISIBLE (-6900 1850);
FORCEPROP 1 LAST NEEDS_NO_SIZE TRUE
J 2
(-6878 1872);
DISPLAY 0.468085 (-6878 1872);
PAINT GREEN (-6878 1872);
DISPLAY INVISIBLE (-6878 1872);
FORCEPROP 1 LAST PATH I11
J 2
(-7025 1930);
DISPLAY 0.723404 (-7025 1930);
PAINT GREEN (-7025 1930);
DISPLAY INVISIBLE (-7025 1930);
FORCEPROP 1 LAST PART_NUMBER BEBL0172Z00
J 0
(-7000 1625);
DISPLAY 0.574468 (-7000 1625);
PAINT GREEN (-7000 1625);
DISPLAY INVISIBLE (-7000 1625);
FORCEADD Q_RES..1
(-5525 1850);
FORCEPROP 1 LAST LOCATION R3088
J 0
(-5575 1900);
DISPLAY 0.978723 (-5575 1900);
FORCEPROP 0 LAST $SEC 1
J 0
(-5575 1950);
DISPLAY 0.680851 (-5575 1950);
PAINT MONO (-5575 1950);
DISPLAY INVISIBLE (-5575 1950);
FORCEPROP 0 LAST CDS_SEC 1
J 0
(-5575 1950);
DISPLAY 1.021277 (-5575 1950);
DISPLAY INVISIBLE (-5575 1950);
FORCEPROP 1 LASTPIN (-5625 1850) $PN 1
J 0
(-5613 1862);
DISPLAY 0.787234 (-5613 1862);
PAINT MONO (-5613 1862);
FORCEPROP 1 LASTPIN (-5425 1850) $PN 2
J 0
(-5463 1862);
DISPLAY 0.787234 (-5463 1862);
PAINT MONO (-5463 1862);
FORCEPROP 1 LAST VALUE 130
J 2
(-5325 1850);
DISPLAY 0.638298 (-5325 1850);
FORCEPROP 1 LAST TOLERANCE 1%
J 0
(-5300 1850);
DISPLAY 0.638298 (-5300 1850);
FORCEPROP 1 LAST MATERIAL CHIP
J 0
(-5675 1800);
DISPLAY 0.638298 (-5675 1800);
FORCEPROP 1 LAST WATTAGE 1/16W
J 2
(-5375 1800);
DISPLAY 0.638298 (-5375 1800);
FORCEPROP 1 LAST PACK_TYPE 0402LF
J 0
(-5225 1850);
DISPLAY 0.638298 (-5225 1850);
FORCEPROP 2 LAST CDS_LIB pure_quanta
J 0
(-5525 1850);
DISPLAY INVISIBLE (-5525 1850);
FORCEPROP 1 LAST PATH I12
J 0
(-5575 2000);
DISPLAY 0.978723 (-5575 2000);
PAINT WHITE (-5575 2000);
DISPLAY INVISIBLE (-5575 2000);
FORCEPROP 1 LAST PART_NUMBER CS11302FB03
J 0
(-5750 1950);
DISPLAY 0.638298 (-5750 1950);
DISPLAY INVISIBLE (-5750 1950);
FORCEADD Q_LED..1
R 2
(-6900 3175);
FORCEPROP 1 LAST LOCATION D75
J 0
(-7000 3100);
DISPLAY 0.723404 (-7000 3100);
PAINT GREEN (-7000 3100);
FORCEPROP 0 LAST $SEC 1
J 0
(-7000 3150);
DISPLAY INVISIBLE (-7000 3150);
FORCEPROP 0 LAST CDS_SEC 1
J 0
(-7000 3150);
DISPLAY INVISIBLE (-7000 3150);
FORCEPROP 0 LASTPIN (-6750 3175) $PN A
J 0
(-6740 3185);
DISPLAY 0.808511 (-6740 3185);
FORCEPROP 0 LASTPIN (-7050 3175) $PN C
J 2
(-7060 3185);
DISPLAY 0.808511 (-7060 3185);
FORCEPROP 0 LAST PACK_TYPE SMLF
J 0
(-7000 3000);
DISPLAY 0.638298 (-7000 3000);
FORCEPROP 1 LAST MATERIAL IC
J 0
(-6875 3000);
DISPLAY 0.723404 (-6875 3000);
PAINT GREEN (-6875 3000);
FORCEPROP 2 LAST COLOR LED_BLUE
J 0
(-7000 3050);
DISPLAY 0.638298 (-7000 3050);
FORCEPROP 2 LAST MANUF_PN LTST-C281TBKT-5A
J 0
(-7000 2900);
DISPLAY 0.638298 (-7000 2900);
FORCEPROP 2 LAST CDS_LIB pure_quanta
J 0
(-6900 3175);
DISPLAY INVISIBLE (-6900 3175);
FORCEPROP 1 LAST NEEDS_NO_SIZE TRUE
J 2
(-6878 3197);
DISPLAY 0.468085 (-6878 3197);
PAINT GREEN (-6878 3197);
DISPLAY INVISIBLE (-6878 3197);
FORCEPROP 1 LAST PATH I13
J 2
(-7025 3255);
DISPLAY 0.723404 (-7025 3255);
PAINT GREEN (-7025 3255);
DISPLAY INVISIBLE (-7025 3255);
FORCEPROP 1 LAST PART_NUMBER BEBL0172Z00
J 0
(-7000 2950);
DISPLAY 0.574468 (-7000 2950);
PAINT GREEN (-7000 2950);
DISPLAY INVISIBLE (-7000 2950);
FORCEADD Q_LED..1
R 2
(-6900 4400);
FORCEPROP 1 LAST LOCATION D74
J 0
(-7000 4325);
DISPLAY 0.723404 (-7000 4325);
PAINT GREEN (-7000 4325);
FORCEPROP 0 LAST $SEC 1
J 0
(-7000 4375);
DISPLAY INVISIBLE (-7000 4375);
FORCEPROP 0 LAST CDS_SEC 1
J 0
(-7000 4375);
DISPLAY INVISIBLE (-7000 4375);
FORCEPROP 0 LASTPIN (-6750 4400) $PN A
J 0
(-6740 4410);
DISPLAY 0.808511 (-6740 4410);
FORCEPROP 0 LASTPIN (-7050 4400) $PN C
J 2
(-7060 4410);
DISPLAY 0.808511 (-7060 4410);
FORCEPROP 2 LAST MANUF_PN LTST-C281TBKT-5A
J 0
(-7000 4125);
DISPLAY 0.638298 (-7000 4125);
FORCEPROP 0 LAST PACK_TYPE SMLF
J 0
(-7000 4225);
DISPLAY 0.638298 (-7000 4225);
FORCEPROP 2 LAST COLOR LED_BLUE
J 0
(-7000 4275);
DISPLAY 0.638298 (-7000 4275);
FORCEPROP 1 LAST MATERIAL IC
J 0
(-6875 4225);
DISPLAY 0.723404 (-6875 4225);
PAINT GREEN (-6875 4225);
FORCEPROP 2 LAST CDS_LIB pure_quanta
J 0
(-6900 4400);
DISPLAY INVISIBLE (-6900 4400);
FORCEPROP 1 LAST NEEDS_NO_SIZE TRUE
J 2
(-6878 4422);
DISPLAY 0.468085 (-6878 4422);
PAINT GREEN (-6878 4422);
DISPLAY INVISIBLE (-6878 4422);
FORCEPROP 1 LAST PATH I14
J 2
(-7025 4480);
DISPLAY 0.723404 (-7025 4480);
PAINT GREEN (-7025 4480);
DISPLAY INVISIBLE (-7025 4480);
FORCEPROP 1 LAST PART_NUMBER BEBL0172Z00
J 0
(-7000 4175);
DISPLAY 0.574468 (-7000 4175);
PAINT GREEN (-7000 4175);
DISPLAY INVISIBLE (-7000 4175);
FORCEADD Q_RES..1
(-5475 3175);
FORCEPROP 1 LAST LOCATION R3089
J 0
(-5525 3225);
DISPLAY 0.978723 (-5525 3225);
FORCEPROP 0 LAST $SEC 1
J 0
(-5525 3275);
DISPLAY 0.680851 (-5525 3275);
PAINT MONO (-5525 3275);
DISPLAY INVISIBLE (-5525 3275);
FORCEPROP 0 LAST CDS_SEC 1
J 0
(-5525 3275);
DISPLAY 1.021277 (-5525 3275);
DISPLAY INVISIBLE (-5525 3275);
FORCEPROP 1 LASTPIN (-5575 3175) $PN 1
J 0
(-5563 3187);
DISPLAY 0.787234 (-5563 3187);
PAINT MONO (-5563 3187);
FORCEPROP 1 LASTPIN (-5375 3175) $PN 2
J 0
(-5413 3187);
DISPLAY 0.787234 (-5413 3187);
PAINT MONO (-5413 3187);
FORCEPROP 1 LAST MATERIAL CHIP
J 0
(-5625 3125);
DISPLAY 0.638298 (-5625 3125);
FORCEPROP 1 LAST TOLERANCE 1%
J 0
(-5250 3175);
DISPLAY 0.638298 (-5250 3175);
FORCEPROP 1 LAST VALUE 130
J 2
(-5275 3175);
DISPLAY 0.638298 (-5275 3175);
FORCEPROP 1 LAST PACK_TYPE 0402LF
J 0
(-5175 3175);
DISPLAY 0.638298 (-5175 3175);
FORCEPROP 1 LAST WATTAGE 1/16W
J 2
(-5325 3125);
DISPLAY 0.638298 (-5325 3125);
FORCEPROP 2 LAST CDS_LIB pure_quanta
J 0
(-5475 3175);
DISPLAY INVISIBLE (-5475 3175);
FORCEPROP 1 LAST PATH I15
J 0
(-5525 3325);
DISPLAY 0.978723 (-5525 3325);
PAINT WHITE (-5525 3325);
DISPLAY INVISIBLE (-5525 3325);
FORCEPROP 1 LAST PART_NUMBER CS11302FB03
J 0
(-5700 3275);
DISPLAY 0.638298 (-5700 3275);
DISPLAY INVISIBLE (-5700 3275);
FORCEADD Q_RES..1
(-5525 4400);
FORCEPROP 1 LAST LOCATION R3087
J 0
(-5575 4450);
DISPLAY 0.978723 (-5575 4450);
FORCEPROP 0 LAST $SEC 1
J 0
(-5575 4500);
DISPLAY 0.680851 (-5575 4500);
PAINT MONO (-5575 4500);
DISPLAY INVISIBLE (-5575 4500);
FORCEPROP 0 LAST CDS_SEC 1
J 0
(-5575 4500);
DISPLAY 1.021277 (-5575 4500);
DISPLAY INVISIBLE (-5575 4500);
FORCEPROP 1 LASTPIN (-5625 4400) $PN 1
J 0
(-5613 4412);
DISPLAY 0.787234 (-5613 4412);
PAINT MONO (-5613 4412);
FORCEPROP 1 LASTPIN (-5425 4400) $PN 2
J 0
(-5463 4412);
DISPLAY 0.787234 (-5463 4412);
PAINT MONO (-5463 4412);
FORCEPROP 1 LAST PACK_TYPE 0402LF
J 0
(-5225 4400);
DISPLAY 0.638298 (-5225 4400);
FORCEPROP 1 LAST MATERIAL CHIP
J 0
(-5675 4350);
DISPLAY 0.638298 (-5675 4350);
FORCEPROP 1 LAST WATTAGE 1/16W
J 2
(-5375 4350);
DISPLAY 0.638298 (-5375 4350);
FORCEPROP 1 LAST TOLERANCE 1%
J 0
(-5300 4400);
DISPLAY 0.638298 (-5300 4400);
FORCEPROP 1 LAST VALUE 130
J 2
(-5325 4400);
DISPLAY 0.638298 (-5325 4400);
FORCEPROP 2 LAST CDS_LIB pure_quanta
J 0
(-5525 4400);
DISPLAY INVISIBLE (-5525 4400);
FORCEPROP 1 LAST PATH I16
J 0
(-5575 4550);
DISPLAY 0.978723 (-5575 4550);
PAINT WHITE (-5575 4550);
DISPLAY INVISIBLE (-5575 4550);
FORCEPROP 1 LAST PART_NUMBER CS11302FB03
J 0
(-5750 4500);
DISPLAY 0.638298 (-5750 4500);
DISPLAY INVISIBLE (-5750 4500);
FORCEADD OFFPAGE..1
(-9075 5400);
PAINT AQUA (-9075 5400);
FORCEPROP 2 LAST $XR0 81 
J 0
(-9296 5400);
DISPLAY 0.638298 (-9296 5400);
PAINT MONO (-9296 5400);
FORCEPROP 2 LAST CDS_LIB standard
J 0
(-9075 5400);
DISPLAY INVISIBLE (-9075 5400);
FORCEPROP 1 LAST OFFPAGE TRUE
J 0
(-8750 5275);
DISPLAY 0.872340 (-8750 5275);
PAINT AQUA (-8750 5275);
DISPLAY INVISIBLE (-8750 5275);
FORCEPROP 1 LAST COMMENT_BODY TRUE
J 0
(-8950 5300);
DISPLAY 0.872340 (-8950 5300);
PAINT GREEN (-8950 5300);
DISPLAY INVISIBLE (-8950 5300);
FORCEPROP 2 LAST PATH I17
J 0
(-9325 5450);
DISPLAY 0.680851 (-9325 5450);
DISPLAY INVISIBLE (-9325 5450);
FORCEADD MOSFET_NCH_DUAL..1
(-7975 5450);
FORCEPROP 1 LAST LOCATION Q79
J 0
(-7824 5424);
DISPLAY 0.723404 (-7824 5424);
PAINT GREEN (-7824 5424);
FORCEPROP 0 LAST $SEC 1
J 0
(-7800 5575);
DISPLAY INVISIBLE (-7800 5575);
FORCEPROP 0 LAST CDS_SEC 1
J 0
(-7800 5575);
DISPLAY INVISIBLE (-7800 5575);
FORCEPROP 0 LASTPIN (-7925 5650) $PN 6
R 1
J 0
(-7935 5660);
DISPLAY 0.808511 (-7935 5660);
FORCEPROP 0 LASTPIN (-8175 5400) $PN 2
J 2
(-8185 5410);
DISPLAY 0.808511 (-8185 5410);
FORCEPROP 0 LASTPIN (-7925 5250) $PN 1
R 1
J 2
(-7935 5240);
DISPLAY 0.808511 (-7935 5240);
FORCEPROP 1 LAST MATERIAL IC
J 0
(-7824 5299);
DISPLAY 0.723404 (-7824 5299);
PAINT GREEN (-7824 5299);
FORCEPROP 2 LAST PART_TYPE SMLF
J 0
(-7800 5525);
DISPLAY 1.021277 (-7800 5525);
FORCEPROP 2 LAST VALUE PJT138K
J 0
(-7800 5475);
DISPLAY 1.021277 (-7800 5475);
FORCEPROP 2 LAST CDS_LIB pure_quanta
J 0
(-7975 5450);
DISPLAY INVISIBLE (-7975 5450);
FORCEPROP 1 LAST CDS_LMAN_SYM_OUTLINE -150,150,150,-150
J 0
(-7975 5450);
DISPLAY 0.468085 (-7975 5450);
PAINT GREEN (-7975 5450);
DISPLAY INVISIBLE (-7975 5450);
FORCEPROP 1 LAST NEEDS_NO_SIZE TRUE
J 0
(-7975 5449);
DISPLAY 0.468085 (-7975 5449);
PAINT GREEN (-7975 5449);
DISPLAY INVISIBLE (-7975 5449);
FORCEPROP 1 LAST PATH I18
J 0
(-7975 5450);
DISPLAY 0.723404 (-7975 5450);
PAINT GREEN (-7975 5450);
DISPLAY INVISIBLE (-7975 5450);
FORCEPROP 1 LAST PART_NUMBER BAM138K0003
J 0
(-7824 5364);
DISPLAY 0.723404 (-7824 5364);
PAINT GREEN (-7824 5364);
DISPLAY INVISIBLE (-7824 5364);
FORCEADD Q_LED..1
R 2
(-6900 5725);
FORCEPROP 1 LAST LOCATION D73
J 0
(-7000 5650);
DISPLAY 0.723404 (-7000 5650);
PAINT GREEN (-7000 5650);
FORCEPROP 0 LAST $SEC 1
J 0
(-7000 5700);
DISPLAY INVISIBLE (-7000 5700);
FORCEPROP 0 LAST CDS_SEC 1
J 0
(-7000 5700);
DISPLAY INVISIBLE (-7000 5700);
FORCEPROP 0 LASTPIN (-6750 5725) $PN A
J 0
(-6740 5735);
DISPLAY 0.808511 (-6740 5735);
FORCEPROP 0 LASTPIN (-7050 5725) $PN C
J 2
(-7060 5735);
DISPLAY 0.808511 (-7060 5735);
FORCEPROP 1 LAST MATERIAL IC
J 0
(-6875 5550);
DISPLAY 0.723404 (-6875 5550);
PAINT GREEN (-6875 5550);
FORCEPROP 2 LAST MANUF_PN LTST-C281TBKT-5A
J 0
(-7000 5450);
DISPLAY 0.638298 (-7000 5450);
FORCEPROP 2 LAST COLOR LED_BLUE
J 0
(-7000 5600);
DISPLAY 0.638298 (-7000 5600);
FORCEPROP 0 LAST PACK_TYPE SMLF
J 0
(-7000 5550);
DISPLAY 0.638298 (-7000 5550);
FORCEPROP 1 LAST NEEDS_NO_SIZE TRUE
J 2
(-6878 5747);
DISPLAY 0.468085 (-6878 5747);
PAINT GREEN (-6878 5747);
DISPLAY INVISIBLE (-6878 5747);
FORCEPROP 2 LAST CDS_LIB pure_quanta
J 0
(-6900 5725);
DISPLAY INVISIBLE (-6900 5725);
FORCEPROP 1 LAST PATH I19
J 2
(-7025 5805);
DISPLAY 0.723404 (-7025 5805);
PAINT GREEN (-7025 5805);
DISPLAY INVISIBLE (-7025 5805);
FORCEPROP 1 LAST PART_NUMBER BEBL0172Z00
J 0
(-7000 5500);
DISPLAY 0.574468 (-7000 5500);
PAINT GREEN (-7000 5500);
DISPLAY INVISIBLE (-7000 5500);
FORCEADD OFFPAGE..1
(-9075 2850);
PAINT AQUA (-9075 2850);
FORCEPROP 2 LAST $XR0 82 
J 0
(-9296 2850);
DISPLAY 0.638298 (-9296 2850);
PAINT MONO (-9296 2850);
FORCEPROP 2 LAST CDS_LIB standard
J 0
(-9075 2850);
DISPLAY INVISIBLE (-9075 2850);
FORCEPROP 1 LAST OFFPAGE TRUE
J 0
(-8750 2725);
DISPLAY 0.872340 (-8750 2725);
PAINT AQUA (-8750 2725);
DISPLAY INVISIBLE (-8750 2725);
FORCEPROP 1 LAST COMMENT_BODY TRUE
J 0
(-8950 2750);
DISPLAY 0.872340 (-8950 2750);
PAINT GREEN (-8950 2750);
DISPLAY INVISIBLE (-8950 2750);
FORCEPROP 2 LAST PATH I2
J 0
(-9325 2900);
DISPLAY 0.680851 (-9325 2900);
DISPLAY INVISIBLE (-9325 2900);
FORCEADD Q_RES..1
(-5550 5725);
FORCEPROP 1 LAST LOCATION R3086
J 0
(-5600 5775);
DISPLAY 0.978723 (-5600 5775);
FORCEPROP 0 LAST $SEC 1
J 0
(-5600 5825);
DISPLAY 0.680851 (-5600 5825);
PAINT MONO (-5600 5825);
DISPLAY INVISIBLE (-5600 5825);
FORCEPROP 0 LAST CDS_SEC 1
J 0
(-5600 5825);
DISPLAY 1.021277 (-5600 5825);
DISPLAY INVISIBLE (-5600 5825);
FORCEPROP 1 LASTPIN (-5650 5725) $PN 1
J 0
(-5638 5737);
DISPLAY 0.787234 (-5638 5737);
PAINT MONO (-5638 5737);
FORCEPROP 1 LASTPIN (-5450 5725) $PN 2
J 0
(-5488 5737);
DISPLAY 0.787234 (-5488 5737);
PAINT MONO (-5488 5737);
FORCEPROP 1 LAST MATERIAL CHIP
J 0
(-5700 5675);
DISPLAY 0.638298 (-5700 5675);
FORCEPROP 1 LAST TOLERANCE 1%
J 0
(-5325 5725);
DISPLAY 0.638298 (-5325 5725);
FORCEPROP 1 LAST PACK_TYPE 0402LF
J 0
(-5250 5725);
DISPLAY 0.638298 (-5250 5725);
FORCEPROP 1 LAST WATTAGE 1/16W
J 2
(-5400 5675);
DISPLAY 0.638298 (-5400 5675);
FORCEPROP 1 LAST VALUE 130
J 2
(-5350 5725);
DISPLAY 0.638298 (-5350 5725);
FORCEPROP 2 LAST CDS_LIB pure_quanta
J 0
(-5550 5725);
DISPLAY INVISIBLE (-5550 5725);
FORCEPROP 1 LAST PATH I20
J 0
(-5600 5875);
DISPLAY 0.978723 (-5600 5875);
PAINT WHITE (-5600 5875);
DISPLAY INVISIBLE (-5600 5875);
FORCEPROP 1 LAST PART_NUMBER CS11302FB03
J 0
(-5775 5825);
DISPLAY 0.638298 (-5775 5825);
DISPLAY INVISIBLE (-5775 5825);
FORCEADD UNIVERSAL_POWER..1
(-4925 2000);
FORCEPROP 3 LASTPIN (-4925 1950) SIG_NAME P3V3_AUX\g
J 0
(-4915 1960);
DISPLAY 0.659574 (-4915 1960);
PAINT MONO (-4915 1960);
DISPLAY INVISIBLE (-4915 1960);
FORCEPROP 1 LAST HDL_POWER P3V3_AUX
J 1
(-4925 2050);
DISPLAY 0.723404 (-4925 2050);
PAINT GREEN (-4925 2050);
FORCEPROP 2 LAST CDS_LIB pure_quanta_power
J 0
(-4925 2000);
DISPLAY INVISIBLE (-4925 2000);
FORCEPROP 1 LAST PATH I21
J 0
(-4875 2025);
DISPLAY 0.872340 (-4875 2025);
PAINT AQUA (-4875 2025);
DISPLAY INVISIBLE (-4875 2025);
FORCEADD OFFPAGE..1
(-4300 2825);
PAINT AQUA (-4300 2825);
FORCEPROP 2 LAST $XR0 81 
J 0
(-4551 2825);
DISPLAY 0.638298 (-4551 2825);
PAINT MONO (-4551 2825);
FORCEPROP 2 LAST CDS_LIB standard
J 0
(-4300 2825);
DISPLAY INVISIBLE (-4300 2825);
FORCEPROP 1 LAST OFFPAGE TRUE
J 0
(-3975 2700);
DISPLAY 0.872340 (-3975 2700);
PAINT AQUA (-3975 2700);
DISPLAY INVISIBLE (-3975 2700);
FORCEPROP 1 LAST COMMENT_BODY TRUE
J 0
(-4175 2725);
DISPLAY 0.872340 (-4175 2725);
PAINT GREEN (-4175 2725);
DISPLAY INVISIBLE (-4175 2725);
FORCEPROP 2 LAST PATH I22
J 0
(-4575 2875);
DISPLAY 0.680851 (-4575 2875);
DISPLAY INVISIBLE (-4575 2875);
FORCEADD MOSFET_NCH_DUAL..1
(-3200 2875);
FORCEPROP 1 LAST LOCATION Q83
J 0
(-3049 2849);
DISPLAY 0.723404 (-3049 2849);
PAINT GREEN (-3049 2849);
FORCEPROP 0 LAST $SEC 1
J 0
(-3025 3000);
DISPLAY INVISIBLE (-3025 3000);
FORCEPROP 0 LAST CDS_SEC 1
J 0
(-3025 3000);
DISPLAY INVISIBLE (-3025 3000);
FORCEPROP 0 LASTPIN (-3150 3075) $PN 6
R 1
J 0
(-3160 3085);
DISPLAY 0.808511 (-3160 3085);
FORCEPROP 0 LASTPIN (-3400 2825) $PN 2
J 2
(-3410 2835);
DISPLAY 0.808511 (-3410 2835);
FORCEPROP 0 LASTPIN (-3150 2675) $PN 1
R 1
J 2
(-3160 2665);
DISPLAY 0.808511 (-3160 2665);
FORCEPROP 2 LAST PART_TYPE SMLF
J 0
(-3025 2950);
DISPLAY 1.021277 (-3025 2950);
FORCEPROP 2 LAST VALUE PJT138K
J 0
(-3025 2900);
DISPLAY 1.021277 (-3025 2900);
FORCEPROP 1 LAST MATERIAL IC
J 0
(-3049 2724);
DISPLAY 0.723404 (-3049 2724);
PAINT GREEN (-3049 2724);
FORCEPROP 2 LAST CDS_LIB pure_quanta
J 0
(-3200 2875);
DISPLAY INVISIBLE (-3200 2875);
FORCEPROP 1 LAST CDS_LMAN_SYM_OUTLINE -150,150,150,-150
J 0
(-3200 2875);
DISPLAY 0.468085 (-3200 2875);
PAINT GREEN (-3200 2875);
DISPLAY INVISIBLE (-3200 2875);
FORCEPROP 1 LAST NEEDS_NO_SIZE TRUE
J 0
(-3200 2874);
DISPLAY 0.468085 (-3200 2874);
PAINT GREEN (-3200 2874);
DISPLAY INVISIBLE (-3200 2874);
FORCEPROP 1 LAST PATH I23
J 0
(-3200 2875);
DISPLAY 0.723404 (-3200 2875);
PAINT GREEN (-3200 2875);
DISPLAY INVISIBLE (-3200 2875);
FORCEPROP 1 LAST PART_NUMBER BAM138K0003
J 0
(-3049 2789);
DISPLAY 0.723404 (-3049 2789);
PAINT GREEN (-3049 2789);
DISPLAY INVISIBLE (-3049 2789);
FORCEADD UNIVERSAL_POWER..1
(-4875 3350);
FORCEPROP 3 LASTPIN (-4875 3300) SIG_NAME P3V3_AUX\g
J 0
(-4865 3310);
DISPLAY 0.659574 (-4865 3310);
PAINT MONO (-4865 3310);
DISPLAY INVISIBLE (-4865 3310);
FORCEPROP 1 LAST HDL_POWER P3V3_AUX
J 1
(-4875 3400);
DISPLAY 0.723404 (-4875 3400);
PAINT GREEN (-4875 3400);
FORCEPROP 2 LAST CDS_LIB pure_quanta_power
J 0
(-4875 3350);
DISPLAY INVISIBLE (-4875 3350);
FORCEPROP 1 LAST PATH I24
J 0
(-4825 3375);
DISPLAY 0.872340 (-4825 3375);
PAINT AQUA (-4825 3375);
DISPLAY INVISIBLE (-4825 3375);
FORCEADD OFFPAGE..1
(-4300 4075);
PAINT AQUA (-4300 4075);
FORCEPROP 2 LAST $XR0 81 
J 0
(-4551 4075);
DISPLAY 0.638298 (-4551 4075);
PAINT MONO (-4551 4075);
FORCEPROP 2 LAST CDS_LIB standard
J 0
(-4300 4075);
DISPLAY INVISIBLE (-4300 4075);
FORCEPROP 1 LAST OFFPAGE TRUE
J 0
(-3975 3950);
DISPLAY 0.872340 (-3975 3950);
PAINT AQUA (-3975 3950);
DISPLAY INVISIBLE (-3975 3950);
FORCEPROP 1 LAST COMMENT_BODY TRUE
J 0
(-4175 3975);
DISPLAY 0.872340 (-4175 3975);
PAINT GREEN (-4175 3975);
DISPLAY INVISIBLE (-4175 3975);
FORCEPROP 2 LAST PATH I25
J 0
(-4575 4125);
DISPLAY 0.680851 (-4575 4125);
DISPLAY INVISIBLE (-4575 4125);
FORCEADD UNIVERSAL_POWER..1
(-4925 4525);
FORCEPROP 3 LASTPIN (-4925 4475) SIG_NAME P3V3_AUX\g
J 0
(-4915 4485);
DISPLAY 0.659574 (-4915 4485);
PAINT MONO (-4915 4485);
DISPLAY INVISIBLE (-4915 4485);
FORCEPROP 1 LAST HDL_POWER P3V3_AUX
J 1
(-4925 4575);
DISPLAY 0.723404 (-4925 4575);
PAINT GREEN (-4925 4575);
FORCEPROP 2 LAST CDS_LIB pure_quanta_power
J 0
(-4925 4525);
DISPLAY INVISIBLE (-4925 4525);
FORCEPROP 1 LAST PATH I26
J 0
(-4875 4550);
DISPLAY 0.872340 (-4875 4550);
PAINT AQUA (-4875 4550);
DISPLAY INVISIBLE (-4875 4550);
FORCEADD MOSFET_NCH_DUAL..2
(-3200 4125);
FORCEPROP 1 LAST LOCATION Q81
J 0
(-3049 4101);
DISPLAY 0.723404 (-3049 4101);
PAINT AQUA (-3049 4101);
FORCEPROP 2 LAST SEC 2
J 0
(-3025 4250);
DISPLAY 0.680851 (-3025 4250);
PAINT MONO (-3025 4250);
DISPLAY INVISIBLE (-3025 4250);
FORCEPROP 2 LASTPIN (-3150 4325) $PN 3
R 1
J 0
(-3160 4335);
DISPLAY 0.723404 (-3160 4335);
PAINT MONO (-3160 4335);
FORCEPROP 2 LASTPIN (-3400 4075) $PN 5
J 2
(-3410 4085);
DISPLAY 0.723404 (-3410 4085);
PAINT MONO (-3410 4085);
FORCEPROP 2 LASTPIN (-3150 3925) $PN 4
R 1
J 2
(-3160 3915);
DISPLAY 0.723404 (-3160 3915);
PAINT MONO (-3160 3915);
FORCEPROP 1 LAST MATERIAL IC
J 0
(-3049 3976);
DISPLAY 0.723404 (-3049 3976);
PAINT SKYBLUE (-3049 3976);
FORCEPROP 2 LAST VALUE PJT138K
J 0
(-3025 4150);
DISPLAY 0.723404 (-3025 4150);
PAINT SKYBLUE (-3025 4150);
FORCEPROP 2 LAST PART_TYPE SMLF
J 0
(-3025 4200);
DISPLAY 1.021277 (-3025 4200);
FORCEPROP 1 LAST CDS_LMAN_SYM_OUTLINE -150,150,150,-150
J 0
(-3200 4125);
DISPLAY 0.468085 (-3200 4125);
PAINT GREEN (-3200 4125);
DISPLAY INVISIBLE (-3200 4125);
FORCEPROP 1 LAST NEEDS_NO_SIZE TRUE
J 0
(-3050 4016);
DISPLAY 0.468085 (-3050 4016);
PAINT GREEN (-3050 4016);
DISPLAY INVISIBLE (-3050 4016);
FORCEPROP 2 LAST CDS_LIB pure_quanta
J 0
(-3200 4125);
DISPLAY INVISIBLE (-3200 4125);
FORCEPROP 2 LAST SEC_TYPE 
J 0
(-3025 4250);
DISPLAY 1.021277 (-3025 4250);
DISPLAY INVISIBLE (-3025 4250);
FORCEPROP 1 LAST PATH I27
J 0
(-3050 3975);
DISPLAY 0.723404 (-3050 3975);
PAINT GREEN (-3050 3975);
DISPLAY INVISIBLE (-3050 3975);
FORCEPROP 1 LAST PART_NUMBER BAM138K0003
J 0
(-3049 4031);
DISPLAY 0.723404 (-3049 4031);
PAINT BLUE (-3049 4031);
DISPLAY INVISIBLE (-3049 4031);
FORCEADD UNIVERSAL_GND..1
(-3150 2525);
FORCEPROP 3 LASTPIN (-3150 2575) SIG_NAME GND\g
J 0
(-3140 2585);
DISPLAY 0.659574 (-3140 2585);
PAINT MONO (-3140 2585);
DISPLAY INVISIBLE (-3140 2585);
FORCEPROP 2 LAST CDS_LIB pure_quanta_power
J 0
(-3150 2525);
DISPLAY INVISIBLE (-3150 2525);
FORCEPROP 1 LAST HDL_POWER GND
J 1
(-3125 2450);
DISPLAY 0.872340 (-3125 2450);
PAINT GREEN (-3125 2450);
DISPLAY INVISIBLE (-3125 2450);
FORCEPROP 1 LAST PATH I28
J 0
(-3075 2525);
DISPLAY 0.872340 (-3075 2525);
PAINT AQUA (-3075 2525);
DISPLAY INVISIBLE (-3075 2525);
FORCEADD UNIVERSAL_GND..1
(-3150 3775);
FORCEPROP 3 LASTPIN (-3150 3825) SIG_NAME GND\g
J 0
(-3140 3835);
DISPLAY 0.659574 (-3140 3835);
PAINT MONO (-3140 3835);
DISPLAY INVISIBLE (-3140 3835);
FORCEPROP 2 LAST CDS_LIB pure_quanta_power
J 0
(-3150 3775);
DISPLAY INVISIBLE (-3150 3775);
FORCEPROP 1 LAST HDL_POWER GND
J 1
(-3125 3700);
DISPLAY 0.872340 (-3125 3700);
PAINT GREEN (-3125 3700);
DISPLAY INVISIBLE (-3125 3700);
FORCEPROP 1 LAST PATH I29
J 0
(-3075 3775);
DISPLAY 0.872340 (-3075 3775);
PAINT AQUA (-3075 3775);
DISPLAY INVISIBLE (-3075 3775);
FORCEADD MOSFET_NCH_DUAL..2
(-7975 1575);
FORCEPROP 1 LAST LOCATION Q80
J 0
(-7824 1551);
DISPLAY 0.723404 (-7824 1551);
PAINT AQUA (-7824 1551);
FORCEPROP 2 LAST SEC 2
J 0
(-7800 1700);
DISPLAY 0.680851 (-7800 1700);
PAINT MONO (-7800 1700);
DISPLAY INVISIBLE (-7800 1700);
FORCEPROP 2 LASTPIN (-7925 1775) $PN 3
R 1
J 0
(-7935 1785);
DISPLAY 0.723404 (-7935 1785);
PAINT MONO (-7935 1785);
FORCEPROP 2 LASTPIN (-8175 1525) $PN 5
J 2
(-8185 1535);
DISPLAY 0.723404 (-8185 1535);
PAINT MONO (-8185 1535);
FORCEPROP 2 LASTPIN (-7925 1375) $PN 4
R 1
J 2
(-7935 1365);
DISPLAY 0.723404 (-7935 1365);
PAINT MONO (-7935 1365);
FORCEPROP 2 LAST VALUE PJT138K
J 0
(-7800 1600);
DISPLAY 0.723404 (-7800 1600);
PAINT SKYBLUE (-7800 1600);
FORCEPROP 1 LAST MATERIAL IC
J 0
(-7824 1426);
DISPLAY 0.723404 (-7824 1426);
PAINT SKYBLUE (-7824 1426);
FORCEPROP 2 LAST PART_TYPE SMLF
J 0
(-7800 1650);
DISPLAY 1.021277 (-7800 1650);
FORCEPROP 1 LAST CDS_LMAN_SYM_OUTLINE -150,150,150,-150
J 0
(-7975 1575);
DISPLAY 0.468085 (-7975 1575);
PAINT GREEN (-7975 1575);
DISPLAY INVISIBLE (-7975 1575);
FORCEPROP 1 LAST NEEDS_NO_SIZE TRUE
J 0
(-7825 1466);
DISPLAY 0.468085 (-7825 1466);
PAINT GREEN (-7825 1466);
DISPLAY INVISIBLE (-7825 1466);
FORCEPROP 2 LAST CDS_LIB pure_quanta
J 0
(-7975 1575);
DISPLAY INVISIBLE (-7975 1575);
FORCEPROP 2 LAST SEC_TYPE 
J 0
(-7800 1700);
DISPLAY 1.021277 (-7800 1700);
DISPLAY INVISIBLE (-7800 1700);
FORCEPROP 1 LAST PATH I3
J 0
(-7825 1425);
DISPLAY 0.723404 (-7825 1425);
PAINT GREEN (-7825 1425);
DISPLAY INVISIBLE (-7825 1425);
FORCEPROP 1 LAST PART_NUMBER BAM138K0003
J 0
(-7824 1481);
DISPLAY 0.723404 (-7824 1481);
PAINT BLUE (-7824 1481);
DISPLAY INVISIBLE (-7824 1481);
FORCEADD Q_LED..1
R 2
(-2125 3150);
FORCEPROP 1 LAST LOCATION D79
J 0
(-2225 3075);
DISPLAY 0.723404 (-2225 3075);
PAINT GREEN (-2225 3075);
FORCEPROP 0 LAST $SEC 1
J 0
(-2225 3125);
DISPLAY INVISIBLE (-2225 3125);
FORCEPROP 0 LAST CDS_SEC 1
J 0
(-2225 3125);
DISPLAY INVISIBLE (-2225 3125);
FORCEPROP 0 LASTPIN (-1975 3150) $PN A
J 0
(-1965 3160);
DISPLAY 0.808511 (-1965 3160);
FORCEPROP 0 LASTPIN (-2275 3150) $PN C
J 2
(-2285 3160);
DISPLAY 0.808511 (-2285 3160);
FORCEPROP 2 LAST MANUF_PN LTST-C281TBKT-5A
J 0
(-2225 2875);
DISPLAY 0.638298 (-2225 2875);
FORCEPROP 0 LAST PACK_TYPE SMLF
J 0
(-2225 2975);
DISPLAY 0.638298 (-2225 2975);
FORCEPROP 2 LAST COLOR LED_BLUE
J 0
(-2225 3025);
DISPLAY 0.638298 (-2225 3025);
FORCEPROP 1 LAST MATERIAL IC
J 0
(-2100 2975);
DISPLAY 0.723404 (-2100 2975);
PAINT GREEN (-2100 2975);
FORCEPROP 1 LAST NEEDS_NO_SIZE TRUE
J 2
(-2103 3172);
DISPLAY 0.468085 (-2103 3172);
PAINT GREEN (-2103 3172);
DISPLAY INVISIBLE (-2103 3172);
FORCEPROP 2 LAST CDS_LIB pure_quanta
J 0
(-2125 3150);
DISPLAY INVISIBLE (-2125 3150);
FORCEPROP 1 LAST PATH I30
J 2
(-2250 3230);
DISPLAY 0.723404 (-2250 3230);
PAINT GREEN (-2250 3230);
DISPLAY INVISIBLE (-2250 3230);
FORCEPROP 1 LAST PART_NUMBER BEBL0172Z00
J 0
(-2225 2925);
DISPLAY 0.574468 (-2225 2925);
PAINT GREEN (-2225 2925);
DISPLAY INVISIBLE (-2225 2925);
FORCEADD UNIVERSAL_GND..1
(-3150 5100);
FORCEPROP 3 LASTPIN (-3150 5150) SIG_NAME GND\g
J 0
(-3140 5160);
DISPLAY 0.659574 (-3140 5160);
PAINT MONO (-3140 5160);
DISPLAY INVISIBLE (-3140 5160);
FORCEPROP 2 LAST CDS_LIB pure_quanta_power
J 0
(-3150 5100);
DISPLAY INVISIBLE (-3150 5100);
FORCEPROP 1 LAST HDL_POWER GND
J 1
(-3125 5025);
DISPLAY 0.872340 (-3125 5025);
PAINT GREEN (-3125 5025);
DISPLAY INVISIBLE (-3125 5025);
FORCEPROP 1 LAST PATH I31
J 0
(-3075 5100);
DISPLAY 0.872340 (-3075 5100);
PAINT AQUA (-3075 5100);
DISPLAY INVISIBLE (-3075 5100);
FORCEADD Q_LED..1
R 2
(-2125 4400);
FORCEPROP 1 LAST LOCATION D78
J 0
(-2225 4325);
DISPLAY 0.723404 (-2225 4325);
PAINT GREEN (-2225 4325);
FORCEPROP 0 LAST $SEC 1
J 0
(-2225 4375);
DISPLAY INVISIBLE (-2225 4375);
FORCEPROP 0 LAST CDS_SEC 1
J 0
(-2225 4375);
DISPLAY INVISIBLE (-2225 4375);
FORCEPROP 0 LASTPIN (-1975 4400) $PN A
J 0
(-1965 4410);
DISPLAY 0.808511 (-1965 4410);
FORCEPROP 0 LASTPIN (-2275 4400) $PN C
J 2
(-2285 4410);
DISPLAY 0.808511 (-2285 4410);
FORCEPROP 2 LAST MANUF_PN LTST-C281TBKT-5A
J 0
(-2225 4125);
DISPLAY 0.638298 (-2225 4125);
FORCEPROP 1 LAST MATERIAL IC
J 0
(-2100 4225);
DISPLAY 0.723404 (-2100 4225);
PAINT GREEN (-2100 4225);
FORCEPROP 2 LAST COLOR LED_BLUE
J 0
(-2225 4275);
DISPLAY 0.638298 (-2225 4275);
FORCEPROP 0 LAST PACK_TYPE SMLF
J 0
(-2225 4225);
DISPLAY 0.638298 (-2225 4225);
FORCEPROP 1 LAST NEEDS_NO_SIZE TRUE
J 2
(-2103 4422);
DISPLAY 0.468085 (-2103 4422);
PAINT GREEN (-2103 4422);
DISPLAY INVISIBLE (-2103 4422);
FORCEPROP 2 LAST CDS_LIB pure_quanta
J 0
(-2125 4400);
DISPLAY INVISIBLE (-2125 4400);
FORCEPROP 1 LAST PATH I32
J 2
(-2250 4480);
DISPLAY 0.723404 (-2250 4480);
PAINT GREEN (-2250 4480);
DISPLAY INVISIBLE (-2250 4480);
FORCEPROP 1 LAST PART_NUMBER BEBL0172Z00
J 0
(-2225 4175);
DISPLAY 0.574468 (-2225 4175);
PAINT GREEN (-2225 4175);
DISPLAY INVISIBLE (-2225 4175);
FORCEADD UNIVERSAL_POWER..1
(-4900 5875);
FORCEPROP 3 LASTPIN (-4900 5825) SIG_NAME P3V3_AUX\g
J 0
(-4890 5835);
DISPLAY 0.659574 (-4890 5835);
PAINT MONO (-4890 5835);
DISPLAY INVISIBLE (-4890 5835);
FORCEPROP 1 LAST HDL_POWER P3V3_AUX
J 1
(-4900 5925);
DISPLAY 0.723404 (-4900 5925);
PAINT GREEN (-4900 5925);
FORCEPROP 2 LAST CDS_LIB pure_quanta_power
J 0
(-4900 5875);
DISPLAY INVISIBLE (-4900 5875);
FORCEPROP 1 LAST PATH I33
J 0
(-4850 5900);
DISPLAY 0.872340 (-4850 5900);
PAINT AQUA (-4850 5900);
DISPLAY INVISIBLE (-4850 5900);
FORCEADD OFFPAGE..1
(-4300 5400);
PAINT AQUA (-4300 5400);
FORCEPROP 2 LAST $XR0 81 
J 0
(-4551 5400);
DISPLAY 0.638298 (-4551 5400);
PAINT MONO (-4551 5400);
FORCEPROP 2 LAST CDS_LIB standard
J 0
(-4300 5400);
DISPLAY INVISIBLE (-4300 5400);
FORCEPROP 1 LAST OFFPAGE TRUE
J 0
(-3975 5275);
DISPLAY 0.872340 (-3975 5275);
PAINT AQUA (-3975 5275);
DISPLAY INVISIBLE (-3975 5275);
FORCEPROP 1 LAST COMMENT_BODY TRUE
J 0
(-4175 5300);
DISPLAY 0.872340 (-4175 5300);
PAINT GREEN (-4175 5300);
DISPLAY INVISIBLE (-4175 5300);
FORCEPROP 2 LAST PATH I34
J 0
(-4575 5450);
DISPLAY 0.680851 (-4575 5450);
DISPLAY INVISIBLE (-4575 5450);
FORCEADD MOSFET_NCH_DUAL..1
(-3200 5450);
FORCEPROP 1 LAST LOCATION Q81
J 0
(-3049 5424);
DISPLAY 0.723404 (-3049 5424);
PAINT GREEN (-3049 5424);
FORCEPROP 0 LAST $SEC 1
J 0
(-3025 5575);
DISPLAY INVISIBLE (-3025 5575);
FORCEPROP 0 LAST CDS_SEC 1
J 0
(-3025 5575);
DISPLAY INVISIBLE (-3025 5575);
FORCEPROP 0 LASTPIN (-3150 5650) $PN 6
R 1
J 0
(-3160 5660);
DISPLAY 0.808511 (-3160 5660);
FORCEPROP 0 LASTPIN (-3400 5400) $PN 2
J 2
(-3410 5410);
DISPLAY 0.808511 (-3410 5410);
FORCEPROP 0 LASTPIN (-3150 5250) $PN 1
R 1
J 2
(-3160 5240);
DISPLAY 0.808511 (-3160 5240);
FORCEPROP 1 LAST MATERIAL IC
J 0
(-3049 5299);
DISPLAY 0.723404 (-3049 5299);
PAINT GREEN (-3049 5299);
FORCEPROP 2 LAST PART_TYPE SMLF
J 0
(-3025 5525);
DISPLAY 1.021277 (-3025 5525);
FORCEPROP 2 LAST VALUE PJT138K
J 0
(-3025 5475);
DISPLAY 1.021277 (-3025 5475);
FORCEPROP 2 LAST CDS_LIB pure_quanta
J 0
(-3200 5450);
DISPLAY INVISIBLE (-3200 5450);
FORCEPROP 1 LAST CDS_LMAN_SYM_OUTLINE -150,150,150,-150
J 0
(-3200 5450);
DISPLAY 0.468085 (-3200 5450);
PAINT GREEN (-3200 5450);
DISPLAY INVISIBLE (-3200 5450);
FORCEPROP 1 LAST NEEDS_NO_SIZE TRUE
J 0
(-3200 5449);
DISPLAY 0.468085 (-3200 5449);
PAINT GREEN (-3200 5449);
DISPLAY INVISIBLE (-3200 5449);
FORCEPROP 1 LAST PATH I35
J 0
(-3200 5450);
DISPLAY 0.723404 (-3200 5450);
PAINT GREEN (-3200 5450);
DISPLAY INVISIBLE (-3200 5450);
FORCEPROP 1 LAST PART_NUMBER BAM138K0003
J 0
(-3049 5364);
DISPLAY 0.723404 (-3049 5364);
PAINT GREEN (-3049 5364);
DISPLAY INVISIBLE (-3049 5364);
FORCEADD Q_LED..1
R 2
(-2125 5725);
FORCEPROP 1 LAST LOCATION D77
J 0
(-2225 5650);
DISPLAY 0.723404 (-2225 5650);
PAINT GREEN (-2225 5650);
FORCEPROP 0 LAST $SEC 1
J 0
(-2225 5700);
DISPLAY INVISIBLE (-2225 5700);
FORCEPROP 0 LAST CDS_SEC 1
J 0
(-2225 5700);
DISPLAY INVISIBLE (-2225 5700);
FORCEPROP 0 LASTPIN (-1975 5725) $PN A
J 0
(-1965 5735);
DISPLAY 0.808511 (-1965 5735);
FORCEPROP 0 LASTPIN (-2275 5725) $PN C
J 2
(-2285 5735);
DISPLAY 0.808511 (-2285 5735);
FORCEPROP 2 LAST MANUF_PN LTST-C281TBKT-5A
J 0
(-2225 5450);
DISPLAY 0.638298 (-2225 5450);
FORCEPROP 0 LAST PACK_TYPE SMLF
J 0
(-2225 5550);
DISPLAY 0.638298 (-2225 5550);
FORCEPROP 2 LAST COLOR LED_BLUE
J 0
(-2225 5600);
DISPLAY 0.638298 (-2225 5600);
FORCEPROP 1 LAST MATERIAL IC
J 0
(-2100 5550);
DISPLAY 0.723404 (-2100 5550);
PAINT GREEN (-2100 5550);
FORCEPROP 2 LAST CDS_LIB pure_quanta
J 0
(-2125 5725);
DISPLAY INVISIBLE (-2125 5725);
FORCEPROP 1 LAST NEEDS_NO_SIZE TRUE
J 2
(-2103 5747);
DISPLAY 0.468085 (-2103 5747);
PAINT GREEN (-2103 5747);
DISPLAY INVISIBLE (-2103 5747);
FORCEPROP 1 LAST PATH I36
J 2
(-2250 5805);
DISPLAY 0.723404 (-2250 5805);
PAINT GREEN (-2250 5805);
DISPLAY INVISIBLE (-2250 5805);
FORCEPROP 1 LAST PART_NUMBER BEBL0172Z00
J 0
(-2225 5500);
DISPLAY 0.574468 (-2225 5500);
PAINT GREEN (-2225 5500);
DISPLAY INVISIBLE (-2225 5500);
FORCEADD Q_RES..1
(-825 3150);
FORCEPROP 1 LAST LOCATION R3091
J 0
(-875 3200);
DISPLAY 0.978723 (-875 3200);
FORCEPROP 0 LAST $SEC 1
J 0
(-875 3250);
DISPLAY 0.680851 (-875 3250);
PAINT MONO (-875 3250);
DISPLAY INVISIBLE (-875 3250);
FORCEPROP 0 LAST CDS_SEC 1
J 0
(-875 3250);
DISPLAY 1.021277 (-875 3250);
DISPLAY INVISIBLE (-875 3250);
FORCEPROP 1 LASTPIN (-925 3150) $PN 1
J 0
(-913 3162);
DISPLAY 0.787234 (-913 3162);
PAINT MONO (-913 3162);
FORCEPROP 1 LASTPIN (-725 3150) $PN 2
J 0
(-763 3162);
DISPLAY 0.787234 (-763 3162);
PAINT MONO (-763 3162);
FORCEPROP 1 LAST VALUE 130
J 2
(-625 3150);
DISPLAY 0.638298 (-625 3150);
FORCEPROP 1 LAST TOLERANCE 1%
J 0
(-600 3150);
DISPLAY 0.638298 (-600 3150);
FORCEPROP 1 LAST MATERIAL CHIP
J 0
(-975 3100);
DISPLAY 0.638298 (-975 3100);
FORCEPROP 1 LAST WATTAGE 1/16W
J 2
(-675 3100);
DISPLAY 0.638298 (-675 3100);
FORCEPROP 1 LAST PACK_TYPE 0402LF
J 0
(-525 3150);
DISPLAY 0.638298 (-525 3150);
FORCEPROP 2 LAST CDS_LIB pure_quanta
J 0
(-825 3150);
DISPLAY INVISIBLE (-825 3150);
FORCEPROP 1 LAST PATH I37
J 0
(-875 3300);
DISPLAY 0.978723 (-875 3300);
PAINT WHITE (-875 3300);
DISPLAY INVISIBLE (-875 3300);
FORCEPROP 1 LAST PART_NUMBER CS11302FB03
J 0
(-1050 3250);
DISPLAY 0.638298 (-1050 3250);
DISPLAY INVISIBLE (-1050 3250);
FORCEADD Q_RES..1
(-825 4400);
FORCEPROP 1 LAST LOCATION R3090
J 0
(-875 4450);
DISPLAY 0.978723 (-875 4450);
FORCEPROP 0 LAST $SEC 1
J 0
(-875 4500);
DISPLAY 0.680851 (-875 4500);
PAINT MONO (-875 4500);
DISPLAY INVISIBLE (-875 4500);
FORCEPROP 0 LAST CDS_SEC 1
J 0
(-875 4500);
DISPLAY 1.021277 (-875 4500);
DISPLAY INVISIBLE (-875 4500);
FORCEPROP 1 LASTPIN (-925 4400) $PN 1
J 0
(-913 4412);
DISPLAY 0.787234 (-913 4412);
PAINT MONO (-913 4412);
FORCEPROP 1 LASTPIN (-725 4400) $PN 2
J 0
(-763 4412);
DISPLAY 0.787234 (-763 4412);
PAINT MONO (-763 4412);
FORCEPROP 1 LAST VALUE 130
J 2
(-625 4400);
DISPLAY 0.638298 (-625 4400);
FORCEPROP 1 LAST TOLERANCE 1%
J 0
(-600 4400);
DISPLAY 0.638298 (-600 4400);
FORCEPROP 1 LAST MATERIAL CHIP
J 0
(-975 4350);
DISPLAY 0.638298 (-975 4350);
FORCEPROP 1 LAST WATTAGE 1/16W
J 2
(-675 4350);
DISPLAY 0.638298 (-675 4350);
FORCEPROP 1 LAST PACK_TYPE 0402LF
J 0
(-525 4400);
DISPLAY 0.638298 (-525 4400);
FORCEPROP 2 LAST CDS_LIB pure_quanta
J 0
(-825 4400);
DISPLAY INVISIBLE (-825 4400);
FORCEPROP 1 LAST PATH I38
J 0
(-875 4550);
DISPLAY 0.978723 (-875 4550);
PAINT WHITE (-875 4550);
DISPLAY INVISIBLE (-875 4550);
FORCEPROP 1 LAST PART_NUMBER CS11302FB03
J 0
(-1050 4500);
DISPLAY 0.638298 (-1050 4500);
DISPLAY INVISIBLE (-1050 4500);
FORCEADD UNIVERSAL_POWER..1
(-150 3300);
FORCEPROP 3 LASTPIN (-150 3250) SIG_NAME P3V3_AUX\g
J 0
(-140 3260);
DISPLAY 0.659574 (-140 3260);
PAINT MONO (-140 3260);
DISPLAY INVISIBLE (-140 3260);
FORCEPROP 1 LAST HDL_POWER P3V3_AUX
J 1
(-150 3350);
DISPLAY 0.723404 (-150 3350);
PAINT GREEN (-150 3350);
FORCEPROP 2 LAST CDS_LIB pure_quanta_power
J 0
(-150 3300);
DISPLAY INVISIBLE (-150 3300);
FORCEPROP 1 LAST PATH I39
J 0
(-100 3325);
DISPLAY 0.872340 (-100 3325);
PAINT AQUA (-100 3325);
DISPLAY INVISIBLE (-100 3325);
FORCEADD UNIVERSAL_GND..1
(-7925 1225);
FORCEPROP 3 LASTPIN (-7925 1275) SIG_NAME GND\g
J 0
(-7915 1285);
DISPLAY 0.659574 (-7915 1285);
PAINT MONO (-7915 1285);
DISPLAY INVISIBLE (-7915 1285);
FORCEPROP 2 LAST CDS_LIB pure_quanta_power
J 0
(-7925 1225);
DISPLAY INVISIBLE (-7925 1225);
FORCEPROP 1 LAST HDL_POWER GND
J 1
(-7900 1150);
DISPLAY 0.872340 (-7900 1150);
PAINT GREEN (-7900 1150);
DISPLAY INVISIBLE (-7900 1150);
FORCEPROP 1 LAST PATH I4
J 0
(-7850 1225);
DISPLAY 0.872340 (-7850 1225);
PAINT AQUA (-7850 1225);
DISPLAY INVISIBLE (-7850 1225);
FORCEADD UNIVERSAL_POWER..1
(-175 4550);
FORCEPROP 3 LASTPIN (-175 4500) SIG_NAME P3V3_AUX\g
J 0
(-165 4510);
DISPLAY 0.659574 (-165 4510);
PAINT MONO (-165 4510);
DISPLAY INVISIBLE (-165 4510);
FORCEPROP 1 LAST HDL_POWER P3V3_AUX
J 1
(-175 4600);
DISPLAY 0.723404 (-175 4600);
PAINT GREEN (-175 4600);
FORCEPROP 2 LAST CDS_LIB pure_quanta_power
J 0
(-175 4550);
DISPLAY INVISIBLE (-175 4550);
FORCEPROP 1 LAST PATH I40
J 0
(-125 4575);
DISPLAY 0.872340 (-125 4575);
PAINT AQUA (-125 4575);
DISPLAY INVISIBLE (-125 4575);
FORCEADD Q_RES..1
(-800 5725);
FORCEPROP 1 LAST LOCATION R3092
J 0
(-850 5775);
DISPLAY 0.978723 (-850 5775);
FORCEPROP 0 LAST $SEC 1
J 0
(-850 5825);
DISPLAY 0.680851 (-850 5825);
PAINT MONO (-850 5825);
DISPLAY INVISIBLE (-850 5825);
FORCEPROP 0 LAST CDS_SEC 1
J 0
(-850 5825);
DISPLAY 1.021277 (-850 5825);
DISPLAY INVISIBLE (-850 5825);
FORCEPROP 1 LASTPIN (-900 5725) $PN 1
J 0
(-888 5737);
DISPLAY 0.787234 (-888 5737);
PAINT MONO (-888 5737);
FORCEPROP 1 LASTPIN (-700 5725) $PN 2
J 0
(-738 5737);
DISPLAY 0.787234 (-738 5737);
PAINT MONO (-738 5737);
FORCEPROP 1 LAST VALUE 130
J 2
(-600 5725);
DISPLAY 0.638298 (-600 5725);
FORCEPROP 1 LAST TOLERANCE 1%
J 0
(-575 5725);
DISPLAY 0.638298 (-575 5725);
FORCEPROP 1 LAST MATERIAL CHIP
J 0
(-950 5675);
DISPLAY 0.638298 (-950 5675);
FORCEPROP 1 LAST WATTAGE 1/16W
J 2
(-650 5675);
DISPLAY 0.638298 (-650 5675);
FORCEPROP 1 LAST PACK_TYPE 0402LF
J 0
(-500 5725);
DISPLAY 0.638298 (-500 5725);
FORCEPROP 2 LAST CDS_LIB pure_quanta
J 0
(-800 5725);
DISPLAY INVISIBLE (-800 5725);
FORCEPROP 1 LAST PATH I41
J 0
(-850 5875);
DISPLAY 0.978723 (-850 5875);
PAINT WHITE (-850 5875);
DISPLAY INVISIBLE (-850 5875);
FORCEPROP 1 LAST PART_NUMBER CS11302FB03
J 0
(-1025 5825);
DISPLAY 0.638298 (-1025 5825);
DISPLAY INVISIBLE (-1025 5825);
FORCEADD UNIVERSAL_POWER..1
(-200 5900);
FORCEPROP 3 LASTPIN (-200 5850) SIG_NAME P3V3_AUX\g
J 0
(-190 5860);
DISPLAY 0.659574 (-190 5860);
PAINT MONO (-190 5860);
DISPLAY INVISIBLE (-190 5860);
FORCEPROP 1 LAST HDL_POWER P3V3_AUX
J 1
(-200 5950);
DISPLAY 0.723404 (-200 5950);
PAINT GREEN (-200 5950);
FORCEPROP 2 LAST CDS_LIB pure_quanta_power
J 0
(-200 5900);
DISPLAY INVISIBLE (-200 5900);
FORCEPROP 1 LAST PATH I42
J 0
(-150 5925);
DISPLAY 0.872340 (-150 5925);
PAINT AQUA (-150 5925);
DISPLAY INVISIBLE (-150 5925);
FORCEADD MOSFET_NCH_DUAL..2
(-3175 1900);
FORCEPROP 1 LAST LOCATION Q83
J 0
(-3024 1876);
DISPLAY 0.723404 (-3024 1876);
PAINT GREEN (-3024 1876);
FORCEPROP 0 LAST $SEC 2
J 0
(-3000 2025);
DISPLAY 0.680851 (-3000 2025);
PAINT MONO (-3000 2025);
DISPLAY INVISIBLE (-3000 2025);
FORCEPROP 0 LAST CDS_SEC 2
J 0
(-3000 2025);
DISPLAY INVISIBLE (-3000 2025);
FORCEPROP 0 LASTPIN (-3125 2100) $PN 3
R 1
J 0
(-3135 2110);
DISPLAY 0.680851 (-3135 2110);
PAINT MONO (-3135 2110);
FORCEPROP 0 LASTPIN (-3375 1850) $PN 5
J 2
(-3385 1860);
DISPLAY 0.680851 (-3385 1860);
PAINT MONO (-3385 1860);
FORCEPROP 0 LASTPIN (-3125 1700) $PN 4
R 1
J 2
(-3135 1690);
DISPLAY 0.680851 (-3135 1690);
PAINT MONO (-3135 1690);
FORCEPROP 1 LAST MATERIAL IC
J 0
(-3024 1751);
DISPLAY 0.723404 (-3024 1751);
PAINT GREEN (-3024 1751);
FORCEPROP 2 LAST VALUE PJT138K
J 0
(-3000 1925);
DISPLAY 1.021277 (-3000 1925);
FORCEPROP 2 LAST PART_TYPE SMLF
J 0
(-3000 1975);
DISPLAY 1.021277 (-3000 1975);
FORCEPROP 2 LAST CDS_LIB pure_quanta
J 0
(-3175 1900);
DISPLAY INVISIBLE (-3175 1900);
FORCEPROP 1 LAST NEEDS_NO_SIZE TRUE
J 0
(-3025 1791);
DISPLAY 0.468085 (-3025 1791);
PAINT GREEN (-3025 1791);
DISPLAY INVISIBLE (-3025 1791);
FORCEPROP 1 LAST CDS_LMAN_SYM_OUTLINE -150,150,150,-150
J 0
(-3175 1900);
DISPLAY 0.468085 (-3175 1900);
PAINT GREEN (-3175 1900);
DISPLAY INVISIBLE (-3175 1900);
FORCEPROP 1 LAST PATH I43
J 0
(-3025 1750);
DISPLAY 0.723404 (-3025 1750);
PAINT GREEN (-3025 1750);
DISPLAY INVISIBLE (-3025 1750);
FORCEPROP 1 LAST PART_NUMBER BAM138K0003
J 0
(-3024 1806);
DISPLAY 0.723404 (-3024 1806);
PAINT GREEN (-3024 1806);
DISPLAY INVISIBLE (-3024 1806);
FORCEADD UNIVERSAL_GND..1
(-7925 2550);
FORCEPROP 3 LASTPIN (-7925 2600) SIG_NAME GND\g
J 0
(-7915 2610);
DISPLAY 0.659574 (-7915 2610);
PAINT MONO (-7915 2610);
DISPLAY INVISIBLE (-7915 2610);
FORCEPROP 2 LAST CDS_LIB pure_quanta_power
J 0
(-7925 2550);
DISPLAY INVISIBLE (-7925 2550);
FORCEPROP 1 LAST HDL_POWER GND
J 1
(-7900 2475);
DISPLAY 0.872340 (-7900 2475);
PAINT GREEN (-7900 2475);
DISPLAY INVISIBLE (-7900 2475);
FORCEPROP 1 LAST PATH I5
J 0
(-7850 2550);
DISPLAY 0.872340 (-7850 2550);
PAINT AQUA (-7850 2550);
DISPLAY INVISIBLE (-7850 2550);
FORCEADD MOSFET_NCH_DUAL..1
(-7975 2900);
FORCEPROP 1 LAST LOCATION Q80
J 0
(-7824 2874);
DISPLAY 0.723404 (-7824 2874);
PAINT GREEN (-7824 2874);
FORCEPROP 0 LAST $SEC 1
J 0
(-7800 3025);
DISPLAY INVISIBLE (-7800 3025);
FORCEPROP 0 LAST CDS_SEC 1
J 0
(-7800 3025);
DISPLAY INVISIBLE (-7800 3025);
FORCEPROP 0 LASTPIN (-7925 3100) $PN 6
R 1
J 0
(-7935 3110);
DISPLAY 0.808511 (-7935 3110);
FORCEPROP 0 LASTPIN (-8175 2850) $PN 2
J 2
(-8185 2860);
DISPLAY 0.808511 (-8185 2860);
FORCEPROP 0 LASTPIN (-7925 2700) $PN 1
R 1
J 2
(-7935 2690);
DISPLAY 0.808511 (-7935 2690);
FORCEPROP 1 LAST MATERIAL IC
J 0
(-7824 2749);
DISPLAY 0.723404 (-7824 2749);
PAINT GREEN (-7824 2749);
FORCEPROP 2 LAST PART_TYPE SMLF
J 0
(-7800 2975);
DISPLAY 1.021277 (-7800 2975);
FORCEPROP 2 LAST VALUE PJT138K
J 0
(-7800 2925);
DISPLAY 1.021277 (-7800 2925);
FORCEPROP 2 LAST CDS_LIB pure_quanta
J 0
(-7975 2900);
DISPLAY INVISIBLE (-7975 2900);
FORCEPROP 1 LAST CDS_LMAN_SYM_OUTLINE -150,150,150,-150
J 0
(-7975 2900);
DISPLAY 0.468085 (-7975 2900);
PAINT GREEN (-7975 2900);
DISPLAY INVISIBLE (-7975 2900);
FORCEPROP 1 LAST NEEDS_NO_SIZE TRUE
J 0
(-7975 2899);
DISPLAY 0.468085 (-7975 2899);
PAINT GREEN (-7975 2899);
DISPLAY INVISIBLE (-7975 2899);
FORCEPROP 1 LAST PATH I6
J 0
(-7975 2900);
DISPLAY 0.723404 (-7975 2900);
PAINT GREEN (-7975 2900);
DISPLAY INVISIBLE (-7975 2900);
FORCEPROP 1 LAST PART_NUMBER BAM138K0003
J 0
(-7824 2814);
DISPLAY 0.723404 (-7824 2814);
PAINT GREEN (-7824 2814);
DISPLAY INVISIBLE (-7824 2814);
FORCEADD OFFPAGE..1
(-9075 4075);
PAINT AQUA (-9075 4075);
FORCEPROP 2 LAST $XR0 82 
J 0
(-9296 4075);
DISPLAY 0.638298 (-9296 4075);
PAINT MONO (-9296 4075);
FORCEPROP 2 LAST CDS_LIB standard
J 0
(-9075 4075);
DISPLAY INVISIBLE (-9075 4075);
FORCEPROP 1 LAST OFFPAGE TRUE
J 0
(-8750 3950);
DISPLAY 0.872340 (-8750 3950);
PAINT AQUA (-8750 3950);
DISPLAY INVISIBLE (-8750 3950);
FORCEPROP 1 LAST COMMENT_BODY TRUE
J 0
(-8950 3975);
DISPLAY 0.872340 (-8950 3975);
PAINT GREEN (-8950 3975);
DISPLAY INVISIBLE (-8950 3975);
FORCEPROP 2 LAST PATH I7
J 0
(-9325 4125);
DISPLAY 0.680851 (-9325 4125);
DISPLAY INVISIBLE (-9325 4125);
FORCEADD MOSFET_NCH_DUAL..2
(-7975 4125);
FORCEPROP 1 LAST LOCATION Q79
J 0
(-7824 4101);
DISPLAY 0.723404 (-7824 4101);
PAINT AQUA (-7824 4101);
FORCEPROP 2 LAST SEC 2
J 0
(-7800 4250);
DISPLAY 0.680851 (-7800 4250);
PAINT MONO (-7800 4250);
DISPLAY INVISIBLE (-7800 4250);
FORCEPROP 2 LASTPIN (-7925 4325) $PN 3
R 1
J 0
(-7935 4335);
DISPLAY 0.723404 (-7935 4335);
PAINT MONO (-7935 4335);
FORCEPROP 2 LASTPIN (-8175 4075) $PN 5
J 2
(-8185 4085);
DISPLAY 0.723404 (-8185 4085);
PAINT MONO (-8185 4085);
FORCEPROP 2 LASTPIN (-7925 3925) $PN 4
R 1
J 2
(-7935 3915);
DISPLAY 0.723404 (-7935 3915);
PAINT MONO (-7935 3915);
FORCEPROP 1 LAST MATERIAL IC
J 0
(-7824 3976);
DISPLAY 0.723404 (-7824 3976);
PAINT SKYBLUE (-7824 3976);
FORCEPROP 2 LAST VALUE PJT138K
J 0
(-7800 4150);
DISPLAY 0.723404 (-7800 4150);
PAINT SKYBLUE (-7800 4150);
FORCEPROP 2 LAST PART_TYPE SMLF
J 0
(-7800 4200);
DISPLAY 1.021277 (-7800 4200);
FORCEPROP 1 LAST CDS_LMAN_SYM_OUTLINE -150,150,150,-150
J 0
(-7975 4125);
DISPLAY 0.468085 (-7975 4125);
PAINT GREEN (-7975 4125);
DISPLAY INVISIBLE (-7975 4125);
FORCEPROP 1 LAST NEEDS_NO_SIZE TRUE
J 0
(-7825 4016);
DISPLAY 0.468085 (-7825 4016);
PAINT GREEN (-7825 4016);
DISPLAY INVISIBLE (-7825 4016);
FORCEPROP 2 LAST CDS_LIB pure_quanta
J 0
(-7975 4125);
DISPLAY INVISIBLE (-7975 4125);
FORCEPROP 2 LAST SEC_TYPE 
J 0
(-7800 4250);
DISPLAY 1.021277 (-7800 4250);
DISPLAY INVISIBLE (-7800 4250);
FORCEPROP 1 LAST PATH I8
J 0
(-7825 3975);
DISPLAY 0.723404 (-7825 3975);
PAINT GREEN (-7825 3975);
DISPLAY INVISIBLE (-7825 3975);
FORCEPROP 1 LAST PART_NUMBER BAM138K0003
J 0
(-7824 4031);
DISPLAY 0.723404 (-7824 4031);
PAINT BLUE (-7824 4031);
DISPLAY INVISIBLE (-7824 4031);
FORCEADD UNIVERSAL_GND..1
(-7925 3775);
FORCEPROP 3 LASTPIN (-7925 3825) SIG_NAME GND\g
J 0
(-7915 3835);
DISPLAY 0.659574 (-7915 3835);
PAINT MONO (-7915 3835);
DISPLAY INVISIBLE (-7915 3835);
FORCEPROP 2 LAST CDS_LIB pure_quanta_power
J 0
(-7925 3775);
DISPLAY INVISIBLE (-7925 3775);
FORCEPROP 1 LAST HDL_POWER GND
J 1
(-7900 3700);
DISPLAY 0.872340 (-7900 3700);
PAINT GREEN (-7900 3700);
DISPLAY INVISIBLE (-7900 3700);
FORCEPROP 1 LAST PATH I9
J 0
(-7850 3775);
DISPLAY 0.872340 (-7850 3775);
PAINT AQUA (-7850 3775);
DISPLAY INVISIBLE (-7850 3775);
FORCEADD QUANTA_TITLE_BLOCK_C..1
(0 0);
FORCEPROP 0 LAST CDS_CON_LAST_MODIFIED Thu Sep 14 16:12:43 2023
J 0
(-1885 15);
DISPLAY INVISIBLE (-1885 15);
FORCEPROP 1 LAST CUSTOM_TXT_CDS <CON_LAST_MODIFIED>
J 0
(-1885 15);
DISPLAY 0.978723 (-1885 15);
FORCEPROP 2 LAST CUSTOM_TXT_CDS <XR_PAGE_TITLE>
J 0
(-7890 5250);
DISPLAY 0.638298 (-7890 5250);
PAINT PINK (-7890 5250);
DISPLAY INVISIBLE (-7890 5250);
FORCEPROP 1 LAST CUSTOM_TXT_CDS <NAME_2>
J 0
(-3175 50);
FORCEPROP 1 LAST CUSTOM_TXT_CDS <NAME_1>
J 0
(-3175 175);
FORCEPROP 1 LAST CUSTOM_TXT_CDS <Q_NUMBER>
J 0
(-1403 103);
DISPLAY 1.212766 (-1403 103);
FORCEPROP 1 LAST CUSTOM_TXT_CDS <Q_PROJ>
J 0
(-2382 102);
DISPLAY 1.212766 (-2382 102);
FORCEPROP 1 LAST CUSTOM_TXT_CDS <Q_REV>
J 0
(-184 103);
DISPLAY 1.212766 (-184 103);
FORCEPROP 1 LAST CUSTOM_TXT_CDS <CON_PAGE_NUM> OF <CON_TOTAL_PAGES>
J 0
(-446 18);
DISPLAY 0.978723 (-446 18);
FORCEPROP 1 LAST Q_TITLE POWER GOOD LED'S 2/3
J 0
(-9366 26);
DISPLAY 2.446809 (-9366 26);
PAINT GREEN (-9366 26);
FORCEPROP 2 LAST PAGE_BORDER TRUE
J 0
(-7890 5250);
DISPLAY 0.638298 (-7890 5250);
PAINT PINK (-7890 5250);
DISPLAY INVISIBLE (-7890 5250);
FORCEPROP 2 LAST CDS_LIB pure_quanta
J 0
(0 0);
DISPLAY INVISIBLE (0 0);
FORCEPROP 1 LAST CDS_LMAN_SYM_OUTLINE -9475,6775,100,-125
J 0
(0 0);
DISPLAY 0.468085 (0 0);
PAINT GREEN (0 0);
DISPLAY INVISIBLE (0 0);
FORCEPROP 2 LAST CDS_XR_PAGE_TITLE CR-256 : @T6G_MB_LIB.T6G(SCH_1):PAGE256
J 0
(-7890 5250);
DISPLAY 0.638298 (-7890 5250);
PAINT PINK (-7890 5250);
DISPLAY INVISIBLE (-7890 5250);
FORCEPROP 1 LAST Q_DEPT BU9
J 1
(-3763 49);
DISPLAY 1.957447 (-3763 49);
PAINT GREEN (-3763 49);
DISPLAY INVISIBLE (-3763 49);
FORCEPROP 1 LAST COMMENT_BODY TRUE
J 0
(12 -13);
DISPLAY 0.978723 (12 -13);
PAINT GREEN (12 -13);
DISPLAY INVISIBLE (12 -13);
WIRE 16 -1 (-7925 5150)(-7925 5250);
WIRE 16 -1 (-4925 1850)(-4925 1950);
WIRE 16 -1 (-4925 1850)(-5425 1850);
WIRE 16 -1 (-4875 3175)(-4875 3300);
WIRE 16 -1 (-4875 3175)(-5375 3175);
WIRE 16 -1 (-4925 4400)(-4925 4475);
WIRE 16 -1 (-4925 4400)(-5425 4400);
WIRE 16 -1 (-3150 2575)(-3150 2675);
WIRE 16 -1 (-3150 3825)(-3150 3925);
WIRE 16 -1 (-3150 5150)(-3150 5250);
WIRE 16 -1 (-4900 5725)(-4900 5825);
WIRE 16 -1 (-4900 5725)(-5450 5725);
WIRE 16 -1 (-150 3150)(-150 3250);
WIRE 16 -1 (-150 3150)(-725 3150);
WIRE 16 -1 (-7925 1275)(-7925 1375);
WIRE 16 -1 (-175 4400)(-175 4500);
WIRE 16 -1 (-175 4400)(-725 4400);
WIRE 16 -1 (-200 5725)(-200 5850);
WIRE 16 -1 (-200 5725)(-700 5725);
WIRE 16 -1 (-7925 2600)(-7925 2700);
WIRE 16 -1 (-7925 3825)(-7925 3925);
WIRE 74 -1 (-6600 4725)(-6600 4925);
WIRE 74 -1 (-9000 4725)(-6600 4725);
WIRE 74 -1 (-6600 4925)(-9000 4925);
WIRE 74 -1 (-9000 4925)(-9000 4725);
WIRE 16 -1 (-7925 4400)(-7050 4400);
FORCEPROP 2 LAST SIG_NAME LED_PWRGD_PVDDCR_CPU0_P0_D
J 0
(-7910 4410);
DISPLAY 0.574468 (-7910 4410);
FORCEPROP 2 LASTPROP $XRERR UNIQUE?
J 0
(-8150 4410);
DISPLAY 0.638298 (-8150 4410);
PAINT MONO (-8150 4410);
DISPLAY INVISIBLE (-8150 4410);
WIRE 16 -1 (-7925 4325)(-7925 4400);
WIRE 74 -1 (-6750 6050)(-6750 6250);
WIRE 74 -1 (-9000 6050)(-6750 6050);
WIRE 74 -1 (-6750 6250)(-9000 6250);
WIRE 74 -1 (-9000 6250)(-9000 6050);
WIRE 16 -1 (-8175 5400)(-9025 5400);
FORCEPROP 2 LAST SIG_NAME FM_LED_PWRGD_PVDD33_S5
J 0
(-8935 5410);
DISPLAY 0.489362 (-8935 5410);
WIRE 74 -1 (-6600 3500)(-6600 3700);
WIRE 74 -1 (-9000 3500)(-6600 3500);
WIRE 74 -1 (-6600 3700)(-9000 3700);
WIRE 74 -1 (-9000 3700)(-9000 3500);
WIRE 16 -1 (-3725 1500)(-3125 1500);
FORCEPROP 2 LAST SIG_NAME NC_Q83_S2
J 0
(-3685 1510);
DISPLAY 0.574468 (-3685 1510);
FORCEPROP 2 LASTPROP $XRERR UNIQUE?
J 0
(-3965 1500);
DISPLAY 0.638298 (-3965 1500);
PAINT MONO (-3965 1500);
DISPLAY INVISIBLE (-3965 1500);
WIRE 16 -1 (-3125 1500)(-3125 1700);
WIRE 16 -1 (-3125 2100)(-3125 2250);
WIRE 16 -1 (-3125 2250)(-3725 2250);
FORCEPROP 2 LAST SIG_NAME NC_Q83_D2
J 0
(-3685 2260);
DISPLAY 0.574468 (-3685 2260);
FORCEPROP 2 LASTPROP $XRERR UNIQUE?
J 0
(-3965 2250);
DISPLAY 0.638298 (-3965 2250);
PAINT MONO (-3965 2250);
DISPLAY INVISIBLE (-3965 2250);
WIRE 16 -1 (-6750 1850)(-5625 1850);
FORCEPROP 2 LAST SIG_NAME LED_PWRGD_PVDDCR_CPU1_P0_R
J 0
(-6610 1860);
DISPLAY 0.723404 (-6610 1860);
FORCEPROP 2 LASTPROP $XRERR UNIQUE?
J 0
(-6850 1860);
DISPLAY 0.638298 (-6850 1860);
PAINT MONO (-6850 1860);
DISPLAY INVISIBLE (-6850 1860);
WIRE 16 -1 (-3400 5400)(-4250 5400);
FORCEPROP 2 LAST SIG_NAME FM_LED_PWRGD_PVDDIO_P0
J 0
(-4235 5410);
DISPLAY 0.723404 (-4235 5410);
WIRE 74 -1 (-1900 4725)(-1900 4925);
WIRE 74 -1 (-4225 4725)(-1900 4725);
WIRE 74 -1 (-1900 4925)(-4225 4925);
WIRE 74 -1 (-4225 4925)(-4225 4725);
WIRE 16 -1 (-3375 1850)(-3900 1850);
FORCEPROP 2 LAST SIG_NAME NC_Q83_G2
J 0
(-3860 1860);
DISPLAY 0.574468 (-3860 1860);
FORCEPROP 2 LASTPROP $XRERR UNIQUE?
J 0
(-4140 1850);
DISPLAY 0.638298 (-4140 1850);
PAINT MONO (-4140 1850);
DISPLAY INVISIBLE (-4140 1850);
WIRE 16 -1 (-3400 2825)(-4250 2825);
FORCEPROP 2 LAST SIG_NAME FM_LED_PWRGD_PVDD18_S5_P0
J 0
(-4185 2835);
DISPLAY 0.574468 (-4185 2835);
WIRE 16 -1 (-6750 3175)(-5575 3175);
FORCEPROP 2 LAST SIG_NAME LED_PWRGD_PVDDCR_SOC_P0_R
J 0
(-6585 3185);
DISPLAY 0.723404 (-6585 3185);
FORCEPROP 2 LASTPROP $XRERR UNIQUE?
J 0
(-6825 3185);
DISPLAY 0.638298 (-6825 3185);
PAINT MONO (-6825 3185);
DISPLAY INVISIBLE (-6825 3185);
WIRE 74 -1 (-1900 3475)(-1900 3675);
WIRE 74 -1 (-4225 3475)(-1900 3475);
WIRE 74 -1 (-1900 3675)(-4225 3675);
WIRE 74 -1 (-4225 3675)(-4225 3475);
WIRE 16 -1 (-3150 4325)(-3150 4400);
FORCEPROP 2 LAST SIG_NAME LED_PWRGD_PVDD11_S3_P0_D
J 0
(-3235 4425);
DISPLAY 0.723404 (-3235 4425);
FORCEPROP 2 LASTPROP $XRERR UNIQUE?
J 0
(-3475 4425);
DISPLAY 0.638298 (-3475 4425);
PAINT MONO (-3475 4425);
DISPLAY INVISIBLE (-3475 4425);
WIRE 16 -1 (-3150 4400)(-2275 4400);
WIRE 16 -1 (-1975 3150)(-925 3150);
FORCEPROP 2 LAST SIG_NAME LED_PWRGD_PVDD18_S5_P0_R
J 0
(-1735 3160);
DISPLAY 0.574468 (-1735 3160);
FORCEPROP 2 LASTPROP $XRERR UNIQUE?
J 0
(-1975 3160);
DISPLAY 0.638298 (-1975 3160);
PAINT MONO (-1975 3160);
DISPLAY INVISIBLE (-1975 3160);
WIRE 16 -1 (-3150 3075)(-3150 3150);
WIRE 16 -1 (-3150 3150)(-2275 3150);
FORCEPROP 2 LAST SIG_NAME LED_PWRGD_PVDD18_S5_P0_D
J 0
(-3135 3160);
DISPLAY 0.574468 (-3135 3160);
FORCEPROP 2 LASTPROP $XRERR UNIQUE?
J 0
(-3375 3160);
DISPLAY 0.638298 (-3375 3160);
PAINT MONO (-3375 3160);
DISPLAY INVISIBLE (-3375 3160);
WIRE 16 -1 (-3400 4075)(-4250 4075);
FORCEPROP 2 LAST SIG_NAME FM_LED_PWRGD_PVDD11_S3_P0
J 0
(-4185 4085);
DISPLAY 0.574468 (-4185 4085);
WIRE 74 -1 (-6600 2175)(-6600 2375);
WIRE 74 -1 (-9000 2175)(-6600 2175);
WIRE 74 -1 (-6600 2375)(-9000 2375);
WIRE 74 -1 (-9000 2375)(-9000 2175);
WIRE 16 -1 (-6750 5725)(-5650 5725);
FORCEPROP 2 LAST SIG_NAME LED_PWRGD_PVDD33_S5_R
J 0
(-6585 5735);
DISPLAY 0.723404 (-6585 5735);
FORCEPROP 2 LASTPROP $XRERR UNIQUE?
J 0
(-6825 5735);
DISPLAY 0.638298 (-6825 5735);
PAINT MONO (-6825 5735);
DISPLAY INVISIBLE (-6825 5735);
WIRE 16 -1 (-1975 4400)(-925 4400);
FORCEPROP 2 LAST SIG_NAME LED_PWRGD_PVDD11_S3_P0_R
J 0
(-1860 4410);
DISPLAY 0.723404 (-1860 4410);
FORCEPROP 2 LASTPROP $XRERR UNIQUE?
J 0
(-2100 4410);
DISPLAY 0.638298 (-2100 4410);
PAINT MONO (-2100 4410);
DISPLAY INVISIBLE (-2100 4410);
WIRE 74 -1 (-1900 6050)(-1900 6250);
WIRE 74 -1 (-4225 6050)(-1900 6050);
WIRE 74 -1 (-1900 6250)(-4225 6250);
WIRE 74 -1 (-4225 6250)(-4225 6050);
WIRE 16 -1 (-3150 5650)(-3150 5725);
FORCEPROP 2 LAST SIG_NAME LED_PWRGD_PVDDIO_P0_D
J 0
(-3160 5735);
DISPLAY 0.723404 (-3160 5735);
FORCEPROP 2 LASTPROP $XRERR UNIQUE?
J 0
(-3400 5735);
DISPLAY 0.638298 (-3400 5735);
PAINT MONO (-3400 5735);
DISPLAY INVISIBLE (-3400 5735);
WIRE 16 -1 (-3150 5725)(-2275 5725);
WIRE 16 -1 (-1975 5725)(-900 5725);
FORCEPROP 2 LAST SIG_NAME LED_PWRGD_PVDDIO_P0_R
J 0
(-1760 5735);
DISPLAY 0.723404 (-1760 5735);
FORCEPROP 2 LASTPROP $XRERR UNIQUE?
J 0
(-2000 5735);
DISPLAY 0.638298 (-2000 5735);
PAINT MONO (-2000 5735);
DISPLAY INVISIBLE (-2000 5735);
WIRE 16 -1 (-6750 4400)(-5625 4400);
FORCEPROP 2 LAST SIG_NAME LED_PWRGD_PVDDCR_CPU0_P0_R
J 0
(-6585 4410);
DISPLAY 0.723404 (-6585 4410);
FORCEPROP 2 LASTPROP $XRERR UNIQUE?
J 0
(-6825 4410);
DISPLAY 0.638298 (-6825 4410);
PAINT MONO (-6825 4410);
DISPLAY INVISIBLE (-6825 4410);
WIRE 16 -1 (-7925 3100)(-7925 3175);
WIRE 16 -1 (-7925 3175)(-7050 3175);
FORCEPROP 2 LAST SIG_NAME LED_PWRGD_PVDDCR_SOC_P0_D
J 0
(-7910 3185);
DISPLAY 0.574468 (-7910 3185);
FORCEPROP 2 LASTPROP $XRERR UNIQUE?
J 0
(-8150 3185);
DISPLAY 0.638298 (-8150 3185);
PAINT MONO (-8150 3185);
DISPLAY INVISIBLE (-8150 3185);
WIRE 16 -1 (-8175 1525)(-9025 1525);
FORCEPROP 2 LAST SIG_NAME FM_LED_PWRGD_PVDDCR_CPU1_P0
J 0
(-9060 1585);
DISPLAY 0.723404 (-9060 1585);
WIRE 16 -1 (-7925 1775)(-7925 1850);
FORCEPROP 2 LAST SIG_NAME LED_PWRGD_PVDDCR_CPU1_P0_D
J 0
(-7910 1885);
DISPLAY 0.574468 (-7910 1885);
FORCEPROP 2 LASTPROP $XRERR UNIQUE?
J 0
(-8150 1885);
DISPLAY 0.638298 (-8150 1885);
PAINT MONO (-8150 1885);
DISPLAY INVISIBLE (-8150 1885);
WIRE 16 -1 (-7925 1850)(-7050 1850);
WIRE 16 -1 (-8175 4075)(-9025 4075);
FORCEPROP 2 LAST SIG_NAME FM_LED_PWRGD_PVDDCR_CPU0_P0
J 0
(-8985 4085);
DISPLAY 0.574468 (-8985 4085);
WIRE 16 -1 (-8175 2850)(-9025 2850);
FORCEPROP 2 LAST SIG_NAME FM_LED_PWRGD_PVDDCR_SOC_P0
J 0
(-8985 2860);
DISPLAY 0.574468 (-8985 2860);
WIRE 16 -1 (-7925 5650)(-7925 5725);
WIRE 16 -1 (-7925 5725)(-7050 5725);
FORCEPROP 2 LAST SIG_NAME LED_PWRGD_PVDD33_S5_D
J 0
(-7910 5735);
DISPLAY 0.723404 (-7910 5735);
FORCEPROP 2 LASTPROP $XRERR UNIQUE?
J 0
(-8150 5735);
DISPLAY 0.638298 (-8150 5735);
PAINT MONO (-8150 5735);
DISPLAY INVISIBLE (-8150 5735);
FORCENOTE
PWRGD_PVDD11_S3_P0            1 = ON
(-4100 4800) 0;
DISPLAY LEFT (-4100 4800);
DISPLAY 1.276596 (-4100 4800);
PAINT WHITE (-4100 4800);
FORCENOTE
PWRGD_PVDD18_S5_P0            1 = ON
(-4100 3550) 0;
DISPLAY LEFT (-4100 3550);
DISPLAY 1.276596 (-4100 3550);
PAINT WHITE (-4100 3550);
FORCENOTE
PWRGD_PVDDCR_CPU1_P0          1 = ON
(-8875 2250) 0;
DISPLAY LEFT (-8875 2250);
DISPLAY 1.276596 (-8875 2250);
PAINT WHITE (-8875 2250);
FORCENOTE
PWRGD_PVDDIO_P0               1 = ON
(-4100 6125) 0;
DISPLAY LEFT (-4100 6125);
DISPLAY 1.276596 (-4100 6125);
PAINT WHITE (-4100 6125);
FORCENOTE
PWRGD_PVDDCR_SOC_P0          1 = ON
(-8875 3575) 0;
DISPLAY LEFT (-8875 3575);
DISPLAY 1.276596 (-8875 3575);
PAINT WHITE (-8875 3575);
FORCENOTE
PWRGD_PVDD33_S5        1 = ON
(-8875 6125) 0;
DISPLAY LEFT (-8875 6125);
DISPLAY 1.276596 (-8875 6125);
PAINT WHITE (-8875 6125);
FORCENOTE
PWRGD_PVDDCR_CPU0_P0   1 = ON
(-8875 4800) 0;
DISPLAY LEFT (-8875 4800);
DISPLAY 1.276596 (-8875 4800);
PAINT WHITE (-8875 4800);
QUIT
